# S9S_MB_2U (Grand Teton) — schematic netlist excerpt (pin names and nets, part order shuffled) for the footprints in the layout excerpt that follows; sources: Cadence DE-HDL packaged netlist, KiCad conversion of 03242023_DA0F0TMBIJ0_F0T_Motherboard_J_brd_V01_OCP.brd

C281  Q_CAP  22UF 4V 20% X6S  pkg C0402  page 77 : A = PVCCIN_CPU1 ; B = GND
C240  Q_CAP  47UF 4V 20% X6S  pkg C0805  page 77 : A = PVCCIN_CPU1 ; B = GND
PR4244  Q_RES  0 5% CHIP  pkg 0402LF  page 292 : A = NC_PVCCINFAON_CPU1_ACSP5 ; B = GND

(kicad_pcb
	(version 20260206)
	(generator "pcbnew")
	(generator_version "10.0")
	(general
		(thickness 1.6)
		(legacy_teardrops no)
	)
	(paper "A4")
	(title_block
		(title "03242023_DA0F0TMBIJ0_F0T_Motherboard_J_brd_V01_OCP.brd")
		(comment 1 "Grand Teton / footprints 880-882 of 6105")
	)
	(layers
		(0 "F.Cu" signal "TOP")
		(4 "In1.Cu" signal "GND")
		(6 "In2.Cu" signal "IN1")
		(8 "In3.Cu" signal "GND1")
		(10 "In4.Cu" signal "IN2")
		(12 "In5.Cu" signal "GND2")
		(14 "In6.Cu" signal "IN3")
		(16 "In7.Cu" signal "GND3")
		(18 "In8.Cu" signal "VCC")
		(20 "In9.Cu" signal "VCC1")
		(22 "In10.Cu" signal "GND4")
		(24 "In11.Cu" signal "IN4")
		(26 "In12.Cu" signal "GND5")
		(28 "In13.Cu" signal "IN5")
		(30 "In14.Cu" signal "GND6")
		(32 "In15.Cu" signal "IN6")
		(34 "In16.Cu" signal "GND7")
		(2 "B.Cu" signal "BOTTOM")
		(9 "F.Adhes" user "F.Adhesive")
		(11 "B.Adhes" user "B.Adhesive")
		(13 "F.Paste" user "Package Geometry/Pastemask Top")
		(15 "B.Paste" user "Package Geometry/Pastemask Bottom")
		(5 "F.SilkS" user "Ref Des/Silkscreen Top")
		(7 "B.SilkS" user "Ref Des/Silkscreen Bottom")
		(1 "F.Mask" user "Board Geometry/Soldermask Top")
		(3 "B.Mask" user "Board Geometry/Soldermask Bottom")
		(17 "Dwgs.User" user "User.Drawings")
		(19 "Cmts.User" user "User.Comments")
		(21 "Eco1.User" user "User.Eco1")
		(23 "Eco2.User" user "User.Eco2")
		(25 "Edge.Cuts" user "Board Geometry/Outline")
		(27 "Margin" user)
		(31 "F.CrtYd" user "Package Geometry/Place Bound Top")
		(29 "B.CrtYd" user "Package Geometry/Place Bound Bottom")
		(35 "F.Fab" user "Ref Des/Assembly Top")
		(33 "B.Fab" user "Ref Des/Assembly Bottom")
	)
	(footprint ""
		(layer "F.Cu")
		(at 117.526816 -252.956568 -90)
		(property "Reference" "C281"
			(at 0 0 270)
			(layer "F.SilkS")
			(hide yes)
			(effects
				(font
					(size 1.27 1.27)
				)
			)
		)
		(property "Value" ""
			(at 0 0 270)
			(layer "F.Fab")
			(effects
				(font
					(size 1.27 1.27)
				)
			)
		)
		(duplicate_pad_numbers_are_jumpers no)
		(fp_line
			(start -0.7874 0.4064)
			(end -0.7874 -0.4064)
			(stroke
				(width 0.1524)
				(type default)
			)
			(layer "F.SilkS")
		)
		(fp_line
			(start 0.7874 0.4064)
			(end -0.7874 0.4064)
			(stroke
				(width 0.1524)
				(type default)
			)
			(layer "F.SilkS")
		)
		(fp_line
			(start -0.7874 -0.4064)
			(end 0.7874 -0.4064)
			(stroke
				(width 0.1524)
				(type default)
			)
			(layer "F.SilkS")
		)
		(fp_line
			(start 0.7874 -0.4064)
			(end 0.7874 0.4064)
			(stroke
				(width 0.1524)
				(type default)
			)
			(layer "F.SilkS")
		)
		(fp_line
			(start -0.67945 0.3048)
			(end -0.67945 -0.305054)
			(stroke
				(width 0.1)
				(type default)
			)
			(layer "F.Fab")
		)
		(fp_line
			(start -0.12065 0.3048)
			(end -0.67945 0.3048)
			(stroke
				(width 0.1)
				(type default)
			)
			(layer "F.Fab")
		)
		(fp_line
			(start 0.120396 0.3048)
			(end 0.120396 0.2794)
			(stroke
				(width 0.1)
				(type default)
			)
			(layer "F.Fab")
		)
		(fp_line
			(start 0.67945 0.3048)
			(end 0.120396 0.3048)
			(stroke
				(width 0.1)
				(type default)
			)
			(layer "F.Fab")
		)
		(fp_line
			(start -0.12065 0.2794)
			(end -0.12065 0.3048)
			(stroke
				(width 0.1)
				(type default)
			)
			(layer "F.Fab")
		)
		(fp_line
			(start 0.120396 0.2794)
			(end -0.12065 0.2794)
			(stroke
				(width 0.1)
				(type default)
			)
			(layer "F.Fab")
		)
		(fp_line
			(start -0.12065 -0.2794)
			(end 0.12065 -0.2794)
			(stroke
				(width 0.1)
				(type default)
			)
			(layer "F.Fab")
		)
		(fp_line
			(start 0.12065 -0.2794)
			(end 0.12065 -0.3048)
			(stroke
				(width 0.1)
				(type default)
			)
			(layer "F.Fab")
		)
		(fp_line
			(start 0.12065 -0.3048)
			(end 0.67945 -0.3048)
			(stroke
				(width 0.1)
				(type default)
			)
			(layer "F.Fab")
		)
		(fp_line
			(start 0.67945 -0.3048)
			(end 0.67945 0.3048)
			(stroke
				(width 0.1)
				(type default)
			)
			(layer "F.Fab")
		)
		(fp_line
			(start -0.67945 -0.305054)
			(end -0.12065 -0.305054)
			(stroke
				(width 0.1)
				(type default)
			)
			(layer "F.Fab")
		)
		(fp_line
			(start -0.12065 -0.305054)
			(end -0.12065 -0.2794)
			(stroke
				(width 0.1)
				(type default)
			)
			(layer "F.Fab")
		)
		(pad "1" smd circle
			(at -0.40005 0 270)
			(size 0 0)
			(layers "F.Cu" "F.Mask" "F.Paste")
			(net "PVCCIN_CPU1")
		)
		(pad "2" smd circle
			(at 0.40005 0 270)
			(size 0 0)
			(layers "F.Cu" "F.Mask" "F.Paste")
			(net "GND")
		)
	)
	(footprint ""
		(layer "F.Cu")
		(at 30.248098 -137.99693 90)
		(property "Reference" "PR4244"
			(at 0 0 90)
			(layer "F.SilkS")
			(hide yes)
			(effects
				(font
					(size 1.27 1.27)
				)
			)
		)
		(property "Value" ""
			(at 0 0 90)
			(layer "F.Fab")
			(effects
				(font
					(size 1.27 1.27)
				)
			)
		)
		(duplicate_pad_numbers_are_jumpers no)
		(fp_line
			(start 0.7874 -0.4064)
			(end 0.7874 0.4064)
			(stroke
				(width 0.1524)
				(type default)
			)
			(layer "F.SilkS")
		)
		(fp_line
			(start -0.7874 -0.4064)
			(end 0.7874 -0.4064)
			(stroke
				(width 0.1524)
				(type default)
			)
			(layer "F.SilkS")
		)
		(fp_line
			(start 0.7874 0.4064)
			(end -0.7874 0.4064)
			(stroke
				(width 0.1524)
				(type default)
			)
			(layer "F.SilkS")
		)
		(fp_line
			(start -0.7874 0.4064)
			(end -0.7874 -0.4064)
			(stroke
				(width 0.1524)
				(type default)
			)
			(layer "F.SilkS")
		)
		(fp_line
			(start -0.12065 -0.305054)
			(end -0.12065 -0.2794)
			(stroke
				(width 0.1)
				(type default)
			)
			(layer "F.Fab")
		)
		(fp_line
			(start -0.67945 -0.305054)
			(end -0.12065 -0.305054)
			(stroke
				(width 0.1)
				(type default)
			)
			(layer "F.Fab")
		)
		(fp_line
			(start 0.67945 -0.3048)
			(end 0.67945 0.3048)
			(stroke
				(width 0.1)
				(type default)
			)
			(layer "F.Fab")
		)
		(fp_line
			(start 0.12065 -0.3048)
			(end 0.67945 -0.3048)
			(stroke
				(width 0.1)
				(type default)
			)
			(layer "F.Fab")
		)
		(fp_line
			(start 0.12065 -0.2794)
			(end 0.12065 -0.3048)
			(stroke
				(width 0.1)
				(type default)
			)
			(layer "F.Fab")
		)
		(fp_line
			(start -0.12065 -0.2794)
			(end 0.12065 -0.2794)
			(stroke
				(width 0.1)
				(type default)
			)
			(layer "F.Fab")
		)
		(fp_line
			(start 0.120396 0.2794)
			(end -0.12065 0.2794)
			(stroke
				(width 0.1)
				(type default)
			)
			(layer "F.Fab")
		)
		(fp_line
			(start -0.12065 0.2794)
			(end -0.12065 0.3048)
			(stroke
				(width 0.1)
				(type default)
			)
			(layer "F.Fab")
		)
		(fp_line
			(start 0.67945 0.3048)
			(end 0.120396 0.3048)
			(stroke
				(width 0.1)
				(type default)
			)
			(layer "F.Fab")
		)
		(fp_line
			(start 0.120396 0.3048)
			(end 0.120396 0.2794)
			(stroke
				(width 0.1)
				(type default)
			)
			(layer "F.Fab")
		)
		(fp_line
			(start -0.12065 0.3048)
			(end -0.67945 0.3048)
			(stroke
				(width 0.1)
				(type default)
			)
			(layer "F.Fab")
		)
		(fp_line
			(start -0.67945 0.3048)
			(end -0.67945 -0.305054)
			(stroke
				(width 0.1)
				(type default)
			)
			(layer "F.Fab")
		)
		(pad "1" smd circle
			(at -0.40005 0 90)
			(size 0 0)
			(layers "F.Cu" "F.Mask" "F.Paste")
			(net "NC_PVCCINFAON_CPU1_ACSP5")
		)
		(pad "2" smd circle
			(at 0.40005 0 90)
			(size 0 0)
			(layers "F.Cu" "F.Mask" "F.Paste")
			(net "GND")
		)
	)
	(footprint ""
		(layer "F.Cu")
		(at 114.91722 -296.05478)
		(property "Reference" "C240"
			(at 0 0 0)
			(layer "F.SilkS")
			(hide yes)
			(effects
				(font
					(size 1.27 1.27)
				)
			)
		)
		(property "Value" ""
			(at 0 0 0)
			(layer "F.Fab")
			(effects
				(font
					(size 1.27 1.27)
				)
			)
		)
		(duplicate_pad_numbers_are_jumpers no)
		(fp_line
			(start -1.524 -0.762)
			(end 1.524 -0.762)
			(stroke
				(width 0.1524)
				(type default)
			)
			(layer "F.SilkS")
		)
		(fp_line
			(start -1.524 0.762)
			(end -1.524 -0.762)
			(stroke
				(width 0.1524)
				(type default)
			)
			(layer "F.SilkS")
		)
		(fp_line
			(start 1.524 -0.762)
			(end 1.524 0.762)
			(stroke
				(width 0.1524)
				(type default)
			)
			(layer "F.SilkS")
		)
		(fp_line
			(start 1.524 0.762)
			(end -1.524 0.762)
			(stroke
				(width 0.1524)
				(type default)
			)
			(layer "F.SilkS")
		)
		(fp_line
			(start -1.1049 -0.724916)
			(end -1.1049 0.724916)
			(stroke
				(width 0.1)
				(type default)
			)
			(layer "F.Fab")
		)
		(fp_line
			(start -1.1049 0.724916)
			(end 1.1049 0.724916)
			(stroke
				(width 0.1)
				(type default)
			)
			(layer "F.Fab")
		)
		(fp_line
			(start 1.1049 -0.724916)
			(end -1.1049 -0.724916)
			(stroke
				(width 0.1)
				(type default)
			)
			(layer "F.Fab")
		)
		(fp_line
			(start 1.1049 0.724916)
			(end 1.1049 -0.724916)
			(stroke
				(width 0.1)
				(type default)
			)
			(layer "F.Fab")
		)
		(pad "1" smd rect
			(at -0.889 0 180)
			(size 1.016 1.27)
			(layers "F.Cu" "F.Mask" "F.Paste")
			(net "PVCCIN_CPU1")
		)
		(pad "2" smd rect
			(at 0.889 0 180)
			(size 1.016 1.27)
			(layers "F.Cu" "F.Mask" "F.Paste")
			(net "GND")
		)
	)
)
